(kicad_pcb
	(version 20260206)
	(generator "pcbnew")
	(generator_version "10.0")
	(general
		(thickness 1.6)
		(legacy_teardrops no)
	)
	(paper "A4")
	(title_block
		(title "01162023_DA0F0TEBIF0_F0T_Expander_BD_F_brd_V02_OCP.brd")
		(comment 1 "Grand Teton / footprints 8590-8596 of 9728")
	)
	(layers
		(0 "F.Cu" signal "TOP")
		(4 "In1.Cu" signal "GND")
		(6 "In2.Cu" signal "VCC")
		(8 "In3.Cu" signal "VCC1")
		(10 "In4.Cu" signal "GND1")
		(12 "In5.Cu" signal "IN1")
		(14 "In6.Cu" signal "GND2")
		(16 "In7.Cu" signal "IN2")
		(18 "In8.Cu" signal "GND3")
		(20 "In9.Cu" signal "IN3")
		(22 "In10.Cu" signal "GND4")
		(24 "In11.Cu" signal "IN4")
		(26 "In12.Cu" signal "GND5")
		(28 "In13.Cu" signal "IN5")
		(30 "In14.Cu" signal "GND6")
		(32 "In15.Cu" signal "IN6")
		(34 "In16.Cu" signal "GND7")
		(2 "B.Cu" signal "BOTTOM")
		(9 "F.Adhes" user "F.Adhesive")
		(11 "B.Adhes" user "B.Adhesive")
		(13 "F.Paste" user "Package Geometry/Pastemask Top")
		(15 "B.Paste" user "Package Geometry/Pastemask Bottom")
		(5 "F.SilkS" user "Ref Des/Silkscreen Top")
		(7 "B.SilkS" user "Ref Des/Silkscreen Bottom")
		(1 "F.Mask" user "Board Geometry/Soldermask Top")
		(3 "B.Mask" user "Board Geometry/Soldermask Bottom")
		(17 "Dwgs.User" user "User.Drawings")
		(19 "Cmts.User" user "User.Comments")
		(21 "Eco1.User" user "User.Eco1")
		(23 "Eco2.User" user "User.Eco2")
		(25 "Edge.Cuts" user "Board Geometry/Outline")
		(27 "Margin" user)
		(31 "F.CrtYd" user "Package Geometry/Place Bound Top")
		(29 "B.CrtYd" user "Package Geometry/Place Bound Bottom")
		(35 "F.Fab" user "Ref Des/Assembly Top")
		(33 "B.Fab" user "Ref Des/Assembly Bottom")
	)
	(footprint ""
		(layer "B.Cu")
		(at 61.597286 -108.465366)
		(property "Reference" "R80"
			(at 0 0 0)
			(layer "B.SilkS")
			(hide yes)
			(effects
				(font
					(size 1.27 1.27)
				)
				(justify mirror)
			)
		)
		(property "Value" ""
			(at 0 0 0)
			(layer "B.Fab")
			(effects
				(font
					(size 1.27 1.27)
				)
				(justify mirror)
			)
		)
		(duplicate_pad_numbers_are_jumpers no)
		(fp_line
			(start -0.7874 -0.4064)
			(end -0.7874 0.4064)
			(stroke
				(width 0.1524)
				(type default)
			)
			(layer "B.SilkS")
		)
		(fp_line
			(start -0.7874 0.4064)
			(end 0.7874 0.4064)
			(stroke
				(width 0.1524)
				(type default)
			)
			(layer "B.SilkS")
		)
		(fp_line
			(start 0.7874 -0.4064)
			(end -0.7874 -0.4064)
			(stroke
				(width 0.1524)
				(type default)
			)
			(layer "B.SilkS")
		)
		(fp_line
			(start 0.7874 0.4064)
			(end 0.7874 -0.4064)
			(stroke
				(width 0.1524)
				(type default)
			)
			(layer "B.SilkS")
		)
		(fp_line
			(start -0.67945 -0.3048)
			(end -0.67945 0.3048)
			(stroke
				(width 0.1)
				(type default)
			)
			(layer "B.Fab")
		)
		(fp_line
			(start -0.67945 0.3048)
			(end -0.120396 0.3048)
			(stroke
				(width 0.1)
				(type default)
			)
			(layer "B.Fab")
		)
		(fp_line
			(start -0.12065 -0.3048)
			(end -0.67945 -0.3048)
			(stroke
				(width 0.1)
				(type default)
			)
			(layer "B.Fab")
		)
		(fp_line
			(start -0.12065 -0.2794)
			(end -0.12065 -0.3048)
			(stroke
				(width 0.1)
				(type default)
			)
			(layer "B.Fab")
		)
		(fp_line
			(start -0.120396 0.2794)
			(end 0.12065 0.2794)
			(stroke
				(width 0.1)
				(type default)
			)
			(layer "B.Fab")
		)
		(fp_line
			(start -0.120396 0.3048)
			(end -0.120396 0.2794)
			(stroke
				(width 0.1)
				(type default)
			)
			(layer "B.Fab")
		)
		(fp_line
			(start 0.12065 -0.305054)
			(end 0.12065 -0.2794)
			(stroke
				(width 0.1)
				(type default)
			)
			(layer "B.Fab")
		)
		(fp_line
			(start 0.12065 -0.2794)
			(end -0.12065 -0.2794)
			(stroke
				(width 0.1)
				(type default)
			)
			(layer "B.Fab")
		)
		(fp_line
			(start 0.12065 0.2794)
			(end 0.12065 0.3048)
			(stroke
				(width 0.1)
				(type default)
			)
			(layer "B.Fab")
		)
		(fp_line
			(start 0.12065 0.3048)
			(end 0.67945 0.3048)
			(stroke
				(width 0.1)
				(type default)
			)
			(layer "B.Fab")
		)
		(fp_line
			(start 0.67945 -0.305054)
			(end 0.12065 -0.305054)
			(stroke
				(width 0.1)
				(type default)
			)
			(layer "B.Fab")
		)
		(fp_line
			(start 0.67945 0.3048)
			(end 0.67945 -0.305054)
			(stroke
				(width 0.1)
				(type default)
			)
			(layer "B.Fab")
		)
		(pad "1" smd circle
			(at 0.40005 0 180)
			(size 0 0)
			(layers "B.Cu" "B.Mask" "B.Paste")
			(net "NIC1_BIF0_N")
		)
		(pad "2" smd circle
			(at -0.40005 0 180)
			(size 0 0)
			(layers "B.Cu" "B.Mask" "B.Paste")
			(net "P3V3_AUX")
		)
	)
	(footprint ""
		(layer "B.Cu")
		(at 113.509806 -293.660068 90)
		(property "Reference" "PC71"
			(at 0 0 90)
			(layer "B.SilkS")
			(hide yes)
			(effects
				(font
					(size 1.27 1.27)
				)
				(justify mirror)
			)
		)
		(property "Value" ""
			(at 0 0 90)
			(layer "B.Fab")
			(effects
				(font
					(size 1.27 1.27)
				)
				(justify mirror)
			)
		)
		(duplicate_pad_numbers_are_jumpers no)
		(fp_line
			(start 4.84378 -2.150618)
			(end 4.53898 -2.150618)
			(stroke
				(width 0.1524)
				(type default)
			)
			(layer "B.SilkS")
		)
		(fp_line
			(start 4.84378 -2.150618)
			(end 4.842256 2.163064)
			(stroke
				(width 0.1524)
				(type default)
			)
			(layer "B.SilkS")
		)
		(fp_line
			(start 4.69138 -2.150618)
			(end 4.692396 2.161032)
			(stroke
				(width 0.1524)
				(type default)
			)
			(layer "B.SilkS")
		)
		(fp_line
			(start 4.53898 -2.150618)
			(end 4.539742 2.152142)
			(stroke
				(width 0.1524)
				(type default)
			)
			(layer "B.SilkS")
		)
		(fp_line
			(start 4.53898 -2.15011)
			(end -4.53898 -2.15011)
			(stroke
				(width 0.1524)
				(type default)
			)
			(layer "B.SilkS")
		)
		(fp_line
			(start -4.53898 -2.15011)
			(end -4.53898 2.15011)
			(stroke
				(width 0.1524)
				(type default)
			)
			(layer "B.SilkS")
		)
		(fp_line
			(start 4.53898 2.15011)
			(end 4.53898 -2.15011)
			(stroke
				(width 0.1524)
				(type default)
			)
			(layer "B.SilkS")
		)
		(fp_line
			(start -4.53898 2.15011)
			(end 4.53898 2.15011)
			(stroke
				(width 0.1524)
				(type default)
			)
			(layer "B.SilkS")
		)
		(fp_line
			(start 4.83108 2.150364)
			(end 4.447794 2.149348)
			(stroke
				(width 0.1524)
				(type default)
			)
			(layer "B.SilkS")
		)
		(fp_line
			(start 3.64998 -2.15011)
			(end -3.64998 -2.15011)
			(stroke
				(width 0.1)
				(type default)
			)
			(layer "B.Fab")
		)
		(fp_line
			(start -3.64998 -2.15011)
			(end -3.64998 2.15011)
			(stroke
				(width 0.1)
				(type default)
			)
			(layer "B.Fab")
		)
		(fp_line
			(start 3.64998 2.15011)
			(end 3.64998 -2.15011)
			(stroke
				(width 0.1)
				(type default)
			)
			(layer "B.Fab")
		)
		(fp_line
			(start -3.64998 2.15011)
			(end 3.64998 2.15011)
			(stroke
				(width 0.1)
				(type default)
			)
			(layer "B.Fab")
		)
		(fp_text user "+"
			(at 6.214872 -0.337058 90)
			(unlocked yes)
			(layer "B.SilkS")
			(effects
				(font
					(size 1.905 1.4224)
					(thickness 0.1524)
				)
				(justify left mirror)
			)
		)
		(fp_text user "-"
			(at -4.313174 -0.094488 90)
			(unlocked yes)
			(layer "B.SilkS")
			(effects
				(font
					(size 1.905 1.4224)
					(thickness 0.1524)
				)
				(justify left mirror)
			)
		)
		(fp_text user "+"
			(at 6.214872 -0.337058 90)
			(unlocked yes)
			(layer "B.Fab")
			(effects
				(font
					(size 1.905 1.4224)
					(thickness 0.1524)
				)
				(justify left mirror)
			)
		)
		(fp_text user "-"
			(at -4.313174 -0.094488 90)
			(unlocked yes)
			(layer "B.Fab")
			(effects
				(font
					(size 1.905 1.4224)
					(thickness 0.1524)
				)
				(justify left mirror)
			)
		)
		(pad "1" smd rect
			(at 3.199892 0 270)
			(size 2.413 2.8194)
			(layers "B.Cu" "B.Mask" "B.Paste")
			(net "P0V8_PEX0")
		)
		(pad "2" smd rect
			(at -3.199892 0 270)
			(size 2.413 2.8194)
			(layers "B.Cu" "B.Mask" "B.Paste")
			(net "GND")
		)
	)
	(footprint ""
		(layer "B.Cu")
		(at 405.100028 -292.099746 90)
		(property "Reference" "C1996"
			(at 0 0 90)
			(layer "B.SilkS")
			(hide yes)
			(effects
				(font
					(size 1.27 1.27)
				)
				(justify mirror)
			)
		)
		(property "Value" ""
			(at 0 0 90)
			(layer "B.Fab")
			(effects
				(font
					(size 1.27 1.27)
				)
				(justify mirror)
			)
		)
		(duplicate_pad_numbers_are_jumpers no)
		(fp_line
			(start 0.299974 -0.150114)
			(end -0.299974 -0.150114)
			(stroke
				(width 0.1)
				(type default)
			)
			(layer "B.Fab")
		)
		(fp_line
			(start -0.299974 -0.150114)
			(end -0.299974 0.150114)
			(stroke
				(width 0.1)
				(type default)
			)
			(layer "B.Fab")
		)
		(fp_line
			(start 0.299974 0.150114)
			(end 0.299974 -0.150114)
			(stroke
				(width 0.1)
				(type default)
			)
			(layer "B.Fab")
		)
		(fp_line
			(start -0.299974 0.150114)
			(end 0.299974 0.150114)
			(stroke
				(width 0.1)
				(type default)
			)
			(layer "B.Fab")
		)
		(pad "1" smd rect
			(at 0.2667 0 270)
			(size 0.3048 0.381)
			(layers "B.Cu" "B.Mask" "B.Paste")
			(net "P0V8_SERDES_VDDA_PEX3")
		)
		(pad "2" smd rect
			(at -0.2667 0 270)
			(size 0.3048 0.381)
			(layers "B.Cu" "B.Mask" "B.Paste")
			(net "GND")
		)
	)
	(footprint ""
		(layer "B.Cu")
		(at 13.067284 -381.024892 90)
		(property "Reference" "C4464"
			(at 0 0 90)
			(layer "B.SilkS")
			(hide yes)
			(effects
				(font
					(size 1.27 1.27)
				)
				(justify mirror)
			)
		)
		(property "Value" ""
			(at 0 0 90)
			(layer "B.Fab")
			(effects
				(font
					(size 1.27 1.27)
				)
				(justify mirror)
			)
		)
		(duplicate_pad_numbers_are_jumpers no)
		(fp_line
			(start 0.7874 -0.4064)
			(end -0.7874 -0.4064)
			(stroke
				(width 0.1524)
				(type default)
			)
			(layer "B.SilkS")
		)
		(fp_line
			(start -0.7874 -0.4064)
			(end -0.7874 0.4064)
			(stroke
				(width 0.1524)
				(type default)
			)
			(layer "B.SilkS")
		)
		(fp_line
			(start 0.7874 0.4064)
			(end 0.7874 -0.4064)
			(stroke
				(width 0.1524)
				(type default)
			)
			(layer "B.SilkS")
		)
		(fp_line
			(start -0.7874 0.4064)
			(end 0.7874 0.4064)
			(stroke
				(width 0.1524)
				(type default)
			)
			(layer "B.SilkS")
		)
		(fp_line
			(start 0.67945 -0.305054)
			(end 0.12065 -0.305054)
			(stroke
				(width 0.1)
				(type default)
			)
			(layer "B.Fab")
		)
		(fp_line
			(start 0.12065 -0.305054)
			(end 0.12065 -0.2794)
			(stroke
				(width 0.1)
				(type default)
			)
			(layer "B.Fab")
		)
		(fp_line
			(start -0.12065 -0.3048)
			(end -0.67945 -0.3048)
			(stroke
				(width 0.1)
				(type default)
			)
			(layer "B.Fab")
		)
		(fp_line
			(start -0.67945 -0.3048)
			(end -0.67945 0.3048)
			(stroke
				(width 0.1)
				(type default)
			)
			(layer "B.Fab")
		)
		(fp_line
			(start 0.12065 -0.2794)
			(end -0.12065 -0.2794)
			(stroke
				(width 0.1)
				(type default)
			)
			(layer "B.Fab")
		)
		(fp_line
			(start -0.12065 -0.2794)
			(end -0.12065 -0.3048)
			(stroke
				(width 0.1)
				(type default)
			)
			(layer "B.Fab")
		)
		(fp_line
			(start 0.12065 0.2794)
			(end 0.12065 0.3048)
			(stroke
				(width 0.1)
				(type default)
			)
			(layer "B.Fab")
		)
		(fp_line
			(start -0.120396 0.2794)
			(end 0.12065 0.2794)
			(stroke
				(width 0.1)
				(type default)
			)
			(layer "B.Fab")
		)
		(fp_line
			(start 0.67945 0.3048)
			(end 0.67945 -0.305054)
			(stroke
				(width 0.1)
				(type default)
			)
			(layer "B.Fab")
		)
		(fp_line
			(start 0.12065 0.3048)
			(end 0.67945 0.3048)
			(stroke
				(width 0.1)
				(type default)
			)
			(layer "B.Fab")
		)
		(fp_line
			(start -0.120396 0.3048)
			(end -0.120396 0.2794)
			(stroke
				(width 0.1)
				(type default)
			)
			(layer "B.Fab")
		)
		(fp_line
			(start -0.67945 0.3048)
			(end -0.120396 0.3048)
			(stroke
				(width 0.1)
				(type default)
			)
			(layer "B.Fab")
		)
		(pad "1" smd circle
			(at 0.40005 0 270)
			(size 0 0)
			(layers "B.Cu" "B.Mask" "B.Paste")
			(net "P3V3_USB_8042")
		)
		(pad "2" smd circle
			(at -0.40005 0 270)
			(size 0 0)
			(layers "B.Cu" "B.Mask" "B.Paste")
			(net "GND")
		)
	)
	(footprint ""
		(layer "B.Cu")
		(at 133.020816 -211.080858 180)
		(property "Reference" "R985"
			(at 0 0 0)
			(layer "B.SilkS")
			(hide yes)
			(effects
				(font
					(size 1.27 1.27)
				)
				(justify mirror)
			)
		)
		(property "Value" ""
			(at 0 0 0)
			(layer "B.Fab")
			(effects
				(font
					(size 1.27 1.27)
				)
				(justify mirror)
			)
		)
		(duplicate_pad_numbers_are_jumpers no)
		(fp_line
			(start 0.7874 0.4064)
			(end 0.7874 -0.4064)
			(stroke
				(width 0.1524)
				(type default)
			)
			(layer "B.SilkS")
		)
		(fp_line
			(start 0.7874 -0.4064)
			(end -0.7874 -0.4064)
			(stroke
				(width 0.1524)
				(type default)
			)
			(layer "B.SilkS")
		)
		(fp_line
			(start -0.7874 0.4064)
			(end 0.7874 0.4064)
			(stroke
				(width 0.1524)
				(type default)
			)
			(layer "B.SilkS")
		)
		(fp_line
			(start -0.7874 -0.4064)
			(end -0.7874 0.4064)
			(stroke
				(width 0.1524)
				(type default)
			)
			(layer "B.SilkS")
		)
		(fp_line
			(start 0.67945 0.3048)
			(end 0.67945 -0.305054)
			(stroke
				(width 0.1)
				(type default)
			)
			(layer "B.Fab")
		)
		(fp_line
			(start 0.67945 -0.305054)
			(end 0.12065 -0.305054)
			(stroke
				(width 0.1)
				(type default)
			)
			(layer "B.Fab")
		)
		(fp_line
			(start 0.12065 0.3048)
			(end 0.67945 0.3048)
			(stroke
				(width 0.1)
				(type default)
			)
			(layer "B.Fab")
		)
		(fp_line
			(start 0.12065 0.2794)
			(end 0.12065 0.3048)
			(stroke
				(width 0.1)
				(type default)
			)
			(layer "B.Fab")
		)
		(fp_line
			(start 0.12065 -0.2794)
			(end -0.12065 -0.2794)
			(stroke
				(width 0.1)
				(type default)
			)
			(layer "B.Fab")
		)
		(fp_line
			(start 0.12065 -0.305054)
			(end 0.12065 -0.2794)
			(stroke
				(width 0.1)
				(type default)
			)
			(layer "B.Fab")
		)
		(fp_line
			(start -0.120396 0.3048)
			(end -0.120396 0.2794)
			(stroke
				(width 0.1)
				(type default)
			)
			(layer "B.Fab")
		)
		(fp_line
			(start -0.120396 0.2794)
			(end 0.12065 0.2794)
			(stroke
				(width 0.1)
				(type default)
			)
			(layer "B.Fab")
		)
		(fp_line
			(start -0.12065 -0.2794)
			(end -0.12065 -0.3048)
			(stroke
				(width 0.1)
				(type default)
			)
			(layer "B.Fab")
		)
		(fp_line
			(start -0.12065 -0.3048)
			(end -0.67945 -0.3048)
			(stroke
				(width 0.1)
				(type default)
			)
			(layer "B.Fab")
		)
		(fp_line
			(start -0.67945 0.3048)
			(end -0.120396 0.3048)
			(stroke
				(width 0.1)
				(type default)
			)
			(layer "B.Fab")
		)
		(fp_line
			(start -0.67945 -0.3048)
			(end -0.67945 0.3048)
			(stroke
				(width 0.1)
				(type default)
			)
			(layer "B.Fab")
		)
		(pad "1" smd circle
			(at 0.40005 0)
			(size 0 0)
			(layers "B.Cu" "B.Mask" "B.Paste")
			(net "UART_PEX0_CLI_BUF_R_TX")
		)
		(pad "2" smd circle
			(at -0.40005 0)
			(size 0 0)
			(layers "B.Cu" "B.Mask" "B.Paste")
			(net "UART_PEX0_CLI_BUF_TX")
		)
	)
	(footprint ""
		(layer "B.Cu")
		(at 125.713236 -260.13791)
		(property "Reference" "PR7140"
			(at 0 0 0)
			(layer "B.SilkS")
			(hide yes)
			(effects
				(font
					(size 1.27 1.27)
				)
				(justify mirror)
			)
		)
		(property "Value" ""
			(at 0 0 0)
			(layer "B.Fab")
			(effects
				(font
					(size 1.27 1.27)
				)
				(justify mirror)
			)
		)
		(duplicate_pad_numbers_are_jumpers no)
		(fp_line
			(start -0.7874 -0.4064)
			(end -0.7874 0.4064)
			(stroke
				(width 0.1524)
				(type default)
			)
			(layer "B.SilkS")
		)
		(fp_line
			(start -0.7874 0.4064)
			(end 0.7874 0.4064)
			(stroke
				(width 0.1524)
				(type default)
			)
			(layer "B.SilkS")
		)
		(fp_line
			(start 0.7874 -0.4064)
			(end -0.7874 -0.4064)
			(stroke
				(width 0.1524)
				(type default)
			)
			(layer "B.SilkS")
		)
		(fp_line
			(start 0.7874 0.4064)
			(end 0.7874 -0.4064)
			(stroke
				(width 0.1524)
				(type default)
			)
			(layer "B.SilkS")
		)
		(fp_line
			(start -0.67945 -0.3048)
			(end -0.67945 0.3048)
			(stroke
				(width 0.1)
				(type default)
			)
			(layer "B.Fab")
		)
		(fp_line
			(start -0.67945 0.3048)
			(end -0.120396 0.3048)
			(stroke
				(width 0.1)
				(type default)
			)
			(layer "B.Fab")
		)
		(fp_line
			(start -0.12065 -0.3048)
			(end -0.67945 -0.3048)
			(stroke
				(width 0.1)
				(type default)
			)
			(layer "B.Fab")
		)
		(fp_line
			(start -0.12065 -0.2794)
			(end -0.12065 -0.3048)
			(stroke
				(width 0.1)
				(type default)
			)
			(layer "B.Fab")
		)
		(fp_line
			(start -0.120396 0.2794)
			(end 0.12065 0.2794)
			(stroke
				(width 0.1)
				(type default)
			)
			(layer "B.Fab")
		)
		(fp_line
			(start -0.120396 0.3048)
			(end -0.120396 0.2794)
			(stroke
				(width 0.1)
				(type default)
			)
			(layer "B.Fab")
		)
		(fp_line
			(start 0.12065 -0.305054)
			(end 0.12065 -0.2794)
			(stroke
				(width 0.1)
				(type default)
			)
			(layer "B.Fab")
		)
		(fp_line
			(start 0.12065 -0.2794)
			(end -0.12065 -0.2794)
			(stroke
				(width 0.1)
				(type default)
			)
			(layer "B.Fab")
		)
		(fp_line
			(start 0.12065 0.2794)
			(end 0.12065 0.3048)
			(stroke
				(width 0.1)
				(type default)
			)
			(layer "B.Fab")
		)
		(fp_line
			(start 0.12065 0.3048)
			(end 0.67945 0.3048)
			(stroke
				(width 0.1)
				(type default)
			)
			(layer "B.Fab")
		)
		(fp_line
			(start 0.67945 -0.305054)
			(end 0.12065 -0.305054)
			(stroke
				(width 0.1)
				(type default)
			)
			(layer "B.Fab")
		)
		(fp_line
			(start 0.67945 0.3048)
			(end 0.67945 -0.305054)
			(stroke
				(width 0.1)
				(type default)
			)
			(layer "B.Fab")
		)
		(pad "1" smd circle
			(at 0.40005 0 180)
			(size 0 0)
			(layers "B.Cu" "B.Mask" "B.Paste")
			(net "P0V8_PEX0_VREF")
		)
		(pad "2" smd circle
			(at -0.40005 0 180)
			(size 0 0)
			(layers "B.Cu" "B.Mask" "B.Paste")
			(net "P0V8_PEX0_SVID")
		)
	)
	(footprint ""
		(layer "B.Cu")
		(at 4.880102 -283.624782)
		(property "Reference" "PC215"
			(at 0 0 0)
			(layer "B.SilkS")
			(hide yes)
			(effects
				(font
					(size 1.27 1.27)
				)
				(justify mirror)
			)
		)
		(property "Value" ""
			(at 0 0 0)
			(layer "B.Fab")
			(effects
				(font
					(size 1.27 1.27)
				)
				(justify mirror)
			)
		)
		(duplicate_pad_numbers_are_jumpers no)
		(fp_line
			(start -1.524 -0.762)
			(end -1.524 0.762)
			(stroke
				(width 0.1524)
				(type default)
			)
			(layer "B.SilkS")
		)
		(fp_line
			(start -1.524 0.762)
			(end 1.524 0.762)
			(stroke
				(width 0.1524)
				(type default)
			)
			(layer "B.SilkS")
		)
		(fp_line
			(start 1.524 -0.762)
			(end -1.524 -0.762)
			(stroke
				(width 0.1524)
				(type default)
			)
			(layer "B.SilkS")
		)
		(fp_line
			(start 1.524 0.762)
			(end 1.524 -0.762)
			(stroke
				(width 0.1524)
				(type default)
			)
			(layer "B.SilkS")
		)
		(fp_line
			(start -1.1049 -0.724916)
			(end 1.1049 -0.724916)
			(stroke
				(width 0.1)
				(type default)
			)
			(layer "B.Fab")
		)
		(fp_line
			(start -1.1049 0.724916)
			(end -1.1049 -0.724916)
			(stroke
				(width 0.1)
				(type default)
			)
			(layer "B.Fab")
		)
		(fp_line
			(start 1.1049 -0.724916)
			(end 1.1049 0.724916)
			(stroke
				(width 0.1)
				(type default)
			)
			(layer "B.Fab")
		)
		(fp_line
			(start 1.1049 0.724916)
			(end -1.1049 0.724916)
			(stroke
				(width 0.1)
				(type default)
			)
			(layer "B.Fab")
		)
		(pad "1" smd rect
			(at 0.889 0)
			(size 1.016 1.27)
			(layers "B.Cu" "B.Mask" "B.Paste")
			(net "P1V25_PEX0_R")
		)
		(pad "2" smd rect
			(at -0.889 0)
			(size 1.016 1.27)
			(layers "B.Cu" "B.Mask" "B.Paste")
			(net "GND")
		)
	)
)
